# SCM (Grand Teton) — schematic netlist excerpt (pin names and nets, part order shuffled) for the footprints in the layout excerpt that follows; sources: Cadence DE-HDL packaged netlist, KiCad conversion of 12092022_DA0F0TMDCD0_F0T_Management_Board_D_brd_V3_OCP.brd

R679  Q_RES  33.2 1% EMPTY  pkg 0402LF  page 13 : A = SPI_BMC_MOSI_IO0_R ; B = QSPI_2_PLD_IO0
R761  Q_RES  33.2 1% CHIP  pkg 0402LF  page 12 : A = UART_6_BMC_TXD ; B = UART_6_BMC_R_TXD

(kicad_pcb
	(version 20260206)
	(generator "pcbnew")
	(generator_version "10.0")
	(general
		(thickness 1.6)
		(legacy_teardrops no)
	)
	(paper "A4")
	(title_block
		(title "12092022_DA0F0TMDCD0_F0T_Management_Board_D_brd_V3_OCP.brd")
		(comment 1 "Grand Teton / footprints 1293-1294 of 1440")
	)
	(layers
		(0 "F.Cu" signal "TOP")
		(4 "In1.Cu" signal "GND")
		(6 "In2.Cu" signal "IN1")
		(8 "In3.Cu" signal "GND1")
		(10 "In4.Cu" signal "IN2")
		(12 "In5.Cu" signal "VCC")
		(14 "In6.Cu" signal "VCC1")
		(16 "In7.Cu" signal "IN3")
		(18 "In8.Cu" signal "GND2")
		(20 "In9.Cu" signal "IN4")
		(22 "In10.Cu" signal "GND3")
		(2 "B.Cu" signal "BOTTOM")
		(9 "F.Adhes" user "F.Adhesive")
		(11 "B.Adhes" user "B.Adhesive")
		(13 "F.Paste" user "Package Geometry/Pastemask Top")
		(15 "B.Paste" user "Package Geometry/Pastemask Bottom")
		(5 "F.SilkS" user "Ref Des/Silkscreen Top")
		(7 "B.SilkS" user "Ref Des/Silkscreen Bottom")
		(1 "F.Mask" user "Board Geometry/Soldermask Top")
		(3 "B.Mask" user "Board Geometry/Soldermask Bottom")
		(17 "Dwgs.User" user "User.Drawings")
		(19 "Cmts.User" user "User.Comments")
		(21 "Eco1.User" user "User.Eco1")
		(23 "Eco2.User" user "User.Eco2")
		(25 "Edge.Cuts" user "Board Geometry/Outline")
		(27 "Margin" user)
		(31 "F.CrtYd" user "Package Geometry/Place Bound Top")
		(29 "B.CrtYd" user "Package Geometry/Place Bound Bottom")
		(35 "F.Fab" user "Ref Des/Assembly Top")
		(33 "B.Fab" user "Ref Des/Assembly Bottom")
	)
	(footprint ""
		(layer "B.Cu")
		(at 39.8526 -30.2768 180)
		(property "Reference" "R761"
			(at 0 0 0)
			(layer "B.SilkS")
			(hide yes)
			(effects
				(font
					(size 1.27 1.27)
				)
				(justify mirror)
			)
		)
		(property "Value" ""
			(at 0 0 0)
			(layer "B.Fab")
			(effects
				(font
					(size 1.27 1.27)
				)
				(justify mirror)
			)
		)
		(duplicate_pad_numbers_are_jumpers no)
		(fp_line
			(start 0.7874 0.4064)
			(end 0.7874 -0.4064)
			(stroke
				(width 0.1524)
				(type default)
			)
			(layer "B.SilkS")
		)
		(fp_line
			(start 0.7874 -0.4064)
			(end -0.7874 -0.4064)
			(stroke
				(width 0.1524)
				(type default)
			)
			(layer "B.SilkS")
		)
		(fp_line
			(start -0.7874 0.4064)
			(end 0.7874 0.4064)
			(stroke
				(width 0.1524)
				(type default)
			)
			(layer "B.SilkS")
		)
		(fp_line
			(start -0.7874 -0.4064)
			(end -0.7874 0.4064)
			(stroke
				(width 0.1524)
				(type default)
			)
			(layer "B.SilkS")
		)
		(fp_line
			(start 0.67945 0.3048)
			(end 0.67945 -0.305054)
			(stroke
				(width 0.1)
				(type default)
			)
			(layer "B.Fab")
		)
		(fp_line
			(start 0.67945 -0.305054)
			(end 0.12065 -0.305054)
			(stroke
				(width 0.1)
				(type default)
			)
			(layer "B.Fab")
		)
		(fp_line
			(start 0.12065 0.3048)
			(end 0.67945 0.3048)
			(stroke
				(width 0.1)
				(type default)
			)
			(layer "B.Fab")
		)
		(fp_line
			(start 0.12065 0.2794)
			(end 0.12065 0.3048)
			(stroke
				(width 0.1)
				(type default)
			)
			(layer "B.Fab")
		)
		(fp_line
			(start 0.12065 -0.2794)
			(end -0.12065 -0.2794)
			(stroke
				(width 0.1)
				(type default)
			)
			(layer "B.Fab")
		)
		(fp_line
			(start 0.12065 -0.305054)
			(end 0.12065 -0.2794)
			(stroke
				(width 0.1)
				(type default)
			)
			(layer "B.Fab")
		)
		(fp_line
			(start -0.120396 0.3048)
			(end -0.120396 0.2794)
			(stroke
				(width 0.1)
				(type default)
			)
			(layer "B.Fab")
		)
		(fp_line
			(start -0.120396 0.2794)
			(end 0.12065 0.2794)
			(stroke
				(width 0.1)
				(type default)
			)
			(layer "B.Fab")
		)
		(fp_line
			(start -0.12065 -0.2794)
			(end -0.12065 -0.3048)
			(stroke
				(width 0.1)
				(type default)
			)
			(layer "B.Fab")
		)
		(fp_line
			(start -0.12065 -0.3048)
			(end -0.67945 -0.3048)
			(stroke
				(width 0.1)
				(type default)
			)
			(layer "B.Fab")
		)
		(fp_line
			(start -0.67945 0.3048)
			(end -0.120396 0.3048)
			(stroke
				(width 0.1)
				(type default)
			)
			(layer "B.Fab")
		)
		(fp_line
			(start -0.67945 -0.3048)
			(end -0.67945 0.3048)
			(stroke
				(width 0.1)
				(type default)
			)
			(layer "B.Fab")
		)
		(pad "1" smd circle
			(at 0.40005 0)
			(size 0 0)
			(layers "B.Cu" "B.Mask" "B.Paste")
			(net "UART_6_BMC_TXD")
		)
		(pad "2" smd circle
			(at -0.40005 0)
			(size 0 0)
			(layers "B.Cu" "B.Mask" "B.Paste")
			(net "UART_6_BMC_R_TXD")
		)
	)
	(footprint ""
		(layer "B.Cu")
		(at 46.9646 -70.9168 180)
		(property "Reference" "R679"
			(at 0 0 0)
			(layer "B.SilkS")
			(hide yes)
			(effects
				(font
					(size 1.27 1.27)
				)
				(justify mirror)
			)
		)
		(property "Value" ""
			(at 0 0 0)
			(layer "B.Fab")
			(effects
				(font
					(size 1.27 1.27)
				)
				(justify mirror)
			)
		)
		(duplicate_pad_numbers_are_jumpers no)
		(fp_line
			(start 0.7874 0.4064)
			(end 0.7874 -0.4064)
			(stroke
				(width 0.1524)
				(type default)
			)
			(layer "B.SilkS")
		)
		(fp_line
			(start 0.7874 -0.4064)
			(end -0.7874 -0.4064)
			(stroke
				(width 0.1524)
				(type default)
			)
			(layer "B.SilkS")
		)
		(fp_line
			(start -0.7874 0.4064)
			(end 0.7874 0.4064)
			(stroke
				(width 0.1524)
				(type default)
			)
			(layer "B.SilkS")
		)
		(fp_line
			(start -0.7874 -0.4064)
			(end -0.7874 0.4064)
			(stroke
				(width 0.1524)
				(type default)
			)
			(layer "B.SilkS")
		)
		(fp_line
			(start 0.67945 0.3048)
			(end 0.67945 -0.305054)
			(stroke
				(width 0.1)
				(type default)
			)
			(layer "B.Fab")
		)
		(fp_line
			(start 0.67945 -0.305054)
			(end 0.12065 -0.305054)
			(stroke
				(width 0.1)
				(type default)
			)
			(layer "B.Fab")
		)
		(fp_line
			(start 0.12065 0.3048)
			(end 0.67945 0.3048)
			(stroke
				(width 0.1)
				(type default)
			)
			(layer "B.Fab")
		)
		(fp_line
			(start 0.12065 0.2794)
			(end 0.12065 0.3048)
			(stroke
				(width 0.1)
				(type default)
			)
			(layer "B.Fab")
		)
		(fp_line
			(start 0.12065 -0.2794)
			(end -0.12065 -0.2794)
			(stroke
				(width 0.1)
				(type default)
			)
			(layer "B.Fab")
		)
		(fp_line
			(start 0.12065 -0.305054)
			(end 0.12065 -0.2794)
			(stroke
				(width 0.1)
				(type default)
			)
			(layer "B.Fab")
		)
		(fp_line
			(start -0.120396 0.3048)
			(end -0.120396 0.2794)
			(stroke
				(width 0.1)
				(type default)
			)
			(layer "B.Fab")
		)
		(fp_line
			(start -0.120396 0.2794)
			(end 0.12065 0.2794)
			(stroke
				(width 0.1)
				(type default)
			)
			(layer "B.Fab")
		)
		(fp_line
			(start -0.12065 -0.2794)
			(end -0.12065 -0.3048)
			(stroke
				(width 0.1)
				(type default)
			)
			(layer "B.Fab")
		)
		(fp_line
			(start -0.12065 -0.3048)
			(end -0.67945 -0.3048)
			(stroke
				(width 0.1)
				(type default)
			)
			(layer "B.Fab")
		)
		(fp_line
			(start -0.67945 0.3048)
			(end -0.120396 0.3048)
			(stroke
				(width 0.1)
				(type default)
			)
			(layer "B.Fab")
		)
		(fp_line
			(start -0.67945 -0.3048)
			(end -0.67945 0.3048)
			(stroke
				(width 0.1)
				(type default)
			)
			(layer "B.Fab")
		)
		(pad "1" smd circle
			(at 0.40005 0)
			(size 0 0)
			(layers "B.Cu" "B.Mask" "B.Paste")
			(net "SPI_BMC_MOSI_IO0_R")
		)
		(pad "2" smd circle
			(at -0.40005 0)
			(size 0 0)
			(layers "B.Cu" "B.Mask" "B.Paste")
			(net "QSPI_2_PLD_IO0")
		)
	)
)
